# T6G (Grand Teton) — schematic netlist excerpt (pin names and nets, part order shuffled) for the footprints in the layout excerpt that follows; sources: Cadence DE-HDL packaged netlist, KiCad conversion of 04192023_DAF0TMB3IC0_F0TG_MB_C_brd_V02_OCP.brd

U276  ISL28022FRZT  ISL28022FRZ-T IC  pkg QFN16_TH_0-5_3X3XH  page 236
  A1  = INA230_2_A1
  A0  = INA230_2_A0
  \ext_clk||int\  = E1S_0_P3V3_ADC_ALERT_R
  \sda||smbdat\  = SMB_INA230_2_3V3AUX_SDA_R1
  \scl|||smbclk\  = SMB_INA230_2_3V3AUX_SCL_R1
  NC0  = NC_INA230_2_NC0
  NC1  = NC_INA230_2_NC1
  NC2  = NC_INA230_2_NC2
  VCC  = P3V3_AUX
  GND  = GND
  VBUS  = P3V3_E1S_0_R
  VINM  = VSENSE_P3V3_INA230_2_INN
  VINP  = VSENSE_P3V3_INA230_2_INP
  NC3  = NC_INA230_2_NC3
  NC4  = NC_INA230_2_NC4
  NC5  = NC_INA230_2_NC5
  TH_GND  = GND

(kicad_pcb
	(version 20260206)
	(generator "pcbnew")
	(generator_version "10.0")
	(general
		(thickness 1.6)
		(legacy_teardrops no)
	)
	(paper "A4")
	(title_block
		(title "04192023_DAF0TMB3IC0_F0TG_MB_C_brd_V02_OCP.brd")
		(comment 1 "Grand Teton / footprints 4678-4678 of 8354")
	)
	(layers
		(0 "F.Cu" signal "TOP")
		(4 "In1.Cu" signal "GND")
		(6 "In2.Cu" signal "IN1")
		(8 "In3.Cu" signal "GND1")
		(10 "In4.Cu" signal "IN2")
		(12 "In5.Cu" signal "GND2")
		(14 "In6.Cu" signal "IN3")
		(16 "In7.Cu" signal "GND3")
		(18 "In8.Cu" signal "VCC")
		(20 "In9.Cu" signal "VCC1")
		(22 "In10.Cu" signal "GND4")
		(24 "In11.Cu" signal "IN4")
		(26 "In12.Cu" signal "GND5")
		(28 "In13.Cu" signal "IN5")
		(30 "In14.Cu" signal "GND6")
		(32 "In15.Cu" signal "IN6")
		(34 "In16.Cu" signal "GND7")
		(2 "B.Cu" signal "BOTTOM")
		(9 "F.Adhes" user "F.Adhesive")
		(11 "B.Adhes" user "B.Adhesive")
		(13 "F.Paste" user "Package Geometry/Pastemask Top")
		(15 "B.Paste" user "Package Geometry/Pastemask Bottom")
		(5 "F.SilkS" user "Ref Des/Silkscreen Top")
		(7 "B.SilkS" user "Ref Des/Silkscreen Bottom")
		(1 "F.Mask" user "Board Geometry/Soldermask Top")
		(3 "B.Mask" user "Board Geometry/Soldermask Bottom")
		(17 "Dwgs.User" user "User.Drawings")
		(19 "Cmts.User" user "User.Comments")
		(21 "Eco1.User" user "User.Eco1")
		(23 "Eco2.User" user "User.Eco2")
		(25 "Edge.Cuts" user "Board Geometry/Outline")
		(27 "Margin" user)
		(31 "F.CrtYd" user "Package Geometry/Place Bound Top")
		(29 "B.CrtYd" user "Package Geometry/Place Bound Bottom")
		(35 "F.Fab" user "Ref Des/Assembly Top")
		(33 "B.Fab" user "Ref Des/Assembly Bottom")
	)
	(footprint ""
		(layer "F.Cu")
		(at 215.259666 -54.455314)
		(property "Reference" "U276"
			(at 4.349242 0.209042 0)
			(unlocked yes)
			(layer "F.SilkS")
			(effects
				(font
					(size 0.7874 0.5842)
					(thickness 0.1524)
				)
			)
		)
		(property "Value" ""
			(at 0 0 0)
			(layer "F.Fab")
			(effects
				(font
					(size 1.27 1.27)
				)
			)
		)
		(duplicate_pad_numbers_are_jumpers no)
		(fp_line
			(start -1.500124 -1.500124)
			(end -1.004062 -1.500124)
			(stroke
				(width 0.1524)
				(type default)
			)
			(layer "F.SilkS")
		)
		(fp_line
			(start -1.500124 -1.004062)
			(end -1.500124 -1.500124)
			(stroke
				(width 0.1524)
				(type default)
			)
			(layer "F.SilkS")
		)
		(fp_line
			(start -1.500124 1.500124)
			(end -1.500124 1.004062)
			(stroke
				(width 0.1524)
				(type default)
			)
			(layer "F.SilkS")
		)
		(fp_line
			(start -1.004062 1.500124)
			(end -1.500124 1.500124)
			(stroke
				(width 0.1524)
				(type default)
			)
			(layer "F.SilkS")
		)
		(fp_line
			(start 1.004062 -1.500124)
			(end 1.500124 -1.500124)
			(stroke
				(width 0.1524)
				(type default)
			)
			(layer "F.SilkS")
		)
		(fp_line
			(start 1.500124 -1.500124)
			(end 1.500124 -1.004062)
			(stroke
				(width 0.1524)
				(type default)
			)
			(layer "F.SilkS")
		)
		(fp_line
			(start 1.500124 1.004062)
			(end 1.500124 1.500124)
			(stroke
				(width 0.1524)
				(type default)
			)
			(layer "F.SilkS")
		)
		(fp_line
			(start 1.500124 1.500124)
			(end 1.004062 1.500124)
			(stroke
				(width 0.1524)
				(type default)
			)
			(layer "F.SilkS")
		)
		(fp_poly
			(pts
				(xy -2.515616 -1.309878) (xy -2.07137 -1.831086) (xy -1.772158 -1.126236)
			)
			(stroke
				(width 0)
				(type default)
			)
			(fill yes)
			(layer "F.SilkS")
		)
		(fp_line
			(start -1.500124 -1.500124)
			(end 1.500124 -1.500124)
			(stroke
				(width 0.1)
				(type default)
			)
			(layer "F.Fab")
		)
		(fp_line
			(start -1.500124 1.500124)
			(end -1.500124 -1.500124)
			(stroke
				(width 0.1)
				(type default)
			)
			(layer "F.Fab")
		)
		(fp_line
			(start 1.500124 -1.500124)
			(end 1.500124 1.500124)
			(stroke
				(width 0.1)
				(type default)
			)
			(layer "F.Fab")
		)
		(fp_line
			(start 1.500124 1.500124)
			(end -1.500124 1.500124)
			(stroke
				(width 0.1)
				(type default)
			)
			(layer "F.Fab")
		)
		(fp_poly
			(pts
				(xy -2.847848 -1.258062) (xy -2.847848 -0.242062) (xy -1.831848 -0.750062)
			)
			(stroke
				(width 0)
				(type default)
			)
			(fill yes)
			(layer "F.Fab")
		)
		(pad "1" smd rect
			(at -1.400048 -0.750062 270)
			(size 0.2286 0.6096)
			(layers "F.Cu" "F.Mask" "F.Paste")
			(net "INA230_2_A1")
		)
		(pad "2" smd rect
			(at -1.400048 -0.249936 270)
			(size 0.2286 0.6096)
			(layers "F.Cu" "F.Mask" "F.Paste")
			(net "INA230_2_A0")
		)
		(pad "3" smd rect
			(at -1.400048 0.249936 270)
			(size 0.2286 0.6096)
			(layers "F.Cu" "F.Mask" "F.Paste")
			(net "E1S_0_P3V3_ADC_ALERT_R")
		)
		(pad "4" smd rect
			(at -1.400048 0.750062 270)
			(size 0.2286 0.6096)
			(layers "F.Cu" "F.Mask" "F.Paste")
			(net "SMB_INA230_2_3V3AUX_SDA_R1")
		)
		(pad "5" smd rect
			(at -0.750062 1.400048)
			(size 0.2286 0.6096)
			(layers "F.Cu" "F.Mask" "F.Paste")
			(net "SMB_INA230_2_3V3AUX_SCL_R1")
		)
		(pad "6" smd rect
			(at -0.249936 1.400048)
			(size 0.2286 0.6096)
			(layers "F.Cu" "F.Mask" "F.Paste")
			(net "NC_INA230_2_NC0")
		)
		(pad "7" smd rect
			(at 0.249936 1.400048)
			(size 0.2286 0.6096)
			(layers "F.Cu" "F.Mask" "F.Paste")
			(net "NC_INA230_2_NC1")
		)
		(pad "8" smd rect
			(at 0.750062 1.400048)
			(size 0.2286 0.6096)
			(layers "F.Cu" "F.Mask" "F.Paste")
			(net "NC_INA230_2_NC2")
		)
		(pad "9" smd rect
			(at 1.400048 0.750062 270)
			(size 0.2286 0.6096)
			(layers "F.Cu" "F.Mask" "F.Paste")
			(net "P3V3_AUX")
		)
		(pad "10" smd rect
			(at 1.400048 0.249936 270)
			(size 0.2286 0.6096)
			(layers "F.Cu" "F.Mask" "F.Paste")
			(net "GND")
		)
		(pad "11" smd rect
			(at 1.400048 -0.249936 270)
			(size 0.2286 0.6096)
			(layers "F.Cu" "F.Mask" "F.Paste")
			(net "P3V3_E1S_0_R")
		)
		(pad "12" smd rect
			(at 1.400048 -0.750062 270)
			(size 0.2286 0.6096)
			(layers "F.Cu" "F.Mask" "F.Paste")
			(net "VSENSE_P3V3_INA230_2_INN")
		)
		(pad "13" smd rect
			(at 0.750062 -1.400048)
			(size 0.2286 0.6096)
			(layers "F.Cu" "F.Mask" "F.Paste")
			(net "VSENSE_P3V3_INA230_2_INP")
		)
		(pad "14" smd rect
			(at 0.249936 -1.400048)
			(size 0.2286 0.6096)
			(layers "F.Cu" "F.Mask" "F.Paste")
			(net "NC_INA230_2_NC3")
		)
		(pad "15" smd rect
			(at -0.249936 -1.400048)
			(size 0.2286 0.6096)
			(layers "F.Cu" "F.Mask" "F.Paste")
			(net "NC_INA230_2_NC4")
		)
		(pad "16" smd rect
			(at -0.750062 -1.400048)
			(size 0.2286 0.6096)
			(layers "F.Cu" "F.Mask" "F.Paste")
			(net "NC_INA230_2_NC5")
		)
		(pad "TH" smd rect
			(at 0 0)
			(size 1.7018 1.7018)
			(layers "F.Cu" "F.Mask" "F.Paste")
			(net "GND")
		)
		(zone
			(layer "F.Cu")
			(hatch none 0.5)
			(connect_pads
				(clearance 0)
			)
			(min_thickness 0.25)
			(keepout
				(tracks not_allowed)
				(vias allowed)
				(pads allowed)
				(copperpour not_allowed)
				(footprints allowed)
			)
			(placement
				(enabled no)
				(sheetname "")
			)
			(fill
				(thermal_gap 0.5)
				(thermal_bridge_width 0.5)
				(island_removal_mode 0)
			)
			(polygon
				(pts
					(xy 214.215218 -54.455314) (xy 214.357966 -54.455314) (xy 214.357966 -53.553614) (xy 216.161366 -53.553614)
					(xy 216.161366 -53.967888) (xy 216.304114 -53.967888) (xy 216.304114 -53.410866) (xy 214.215218 -53.410866)
				)
			)
		)
	)
)
